(kicad_pcb
	(version 20241229)
	(generator "pcbnew")
	(generator_version "9.0")
	(general
		(thickness 1.61)
		(legacy_teardrops no)
	)
	(paper "A3")
	(title_block
		(title "SO-DIMM DDR5 Tester")
		(date "2025-11-26")
		(rev "1.3.0")
		(comment 9 "footprints 246-250 of 627")
	)
	(layers
		(0 "F.Cu" signal)
		(4 "In1.Cu" power)
		(6 "In2.Cu" mixed)
		(8 "In3.Cu" power)
		(10 "In4.Cu" mixed)
		(12 "In5.Cu" power)
		(14 "In6.Cu" mixed)
		(16 "In7.Cu" power)
		(18 "In8.Cu" power)
		(20 "In9.Cu" mixed)
		(22 "In10.Cu" power)
		(2 "B.Cu" signal)
		(9 "F.Adhes" user "F.Adhesive")
		(11 "B.Adhes" user "B.Adhesive")
		(13 "F.Paste" user)
		(15 "B.Paste" user)
		(5 "F.SilkS" user "F.Silkscreen")
		(7 "B.SilkS" user "B.Silkscreen")
		(1 "F.Mask" user)
		(3 "B.Mask" user)
		(17 "Dwgs.User" user "User.Drawings")
		(19 "Cmts.User" user "User.Comments")
		(21 "Eco1.User" user "User.Eco1")
		(23 "Eco2.User" user "User.Eco2")
		(25 "Edge.Cuts" user)
		(27 "Margin" user)
		(31 "F.CrtYd" user "F.Courtyard")
		(29 "B.CrtYd" user "B.Courtyard")
		(35 "F.Fab" user)
		(33 "B.Fab" user)
	)
	(footprint "antmicro-footprints:C_0402_1005Metric"
		(layer "F.Cu")
		(at 183.120107 181.815)
		(descr "Capacitor SMD 0402")
		(tags "capacitor SMD 0402")
		(property "Reference" "C199"
			(at 0 -0.699 0)
			(layer "F.SilkS")
			(hide yes)
			(effects
				(font
					(size 0.7 0.7)
					(thickness 0.15)
				)
				(justify left bottom)
			)
		)
		(property "Value" "C_100n_0402"
			(at -1.022927 2.155213 0)
			(layer "F.Fab")
			(effects
				(font
					(size 0.7 0.7)
					(thickness 0.15)
				)
				(justify left bottom)
			)
		)
		(property "Datasheet" "https://www.murata.com/products/productdetail?partno=GRM155R61H104KE14%23"
			(at 0 0 0)
			(layer "F.Fab")
			(hide yes)
			(effects
				(font
					(size 1.27 1.27)
					(thickness 0.15)
				)
			)
		)
		(property "Author" "Antmicro"
			(at 0 0 0)
			(layer "F.Fab")
			(hide yes)
			(effects
				(font
					(size 1 1)
					(thickness 0.15)
				)
			)
		)
		(property "Dielectric" "X5R"
			(at 0 0 0)
			(layer "F.Fab")
			(hide yes)
			(effects
				(font
					(size 1 1)
					(thickness 0.15)
				)
			)
		)
		(property "License" "Apache-2.0"
			(at 0 0 0)
			(layer "F.Fab")
			(hide yes)
			(effects
				(font
					(size 1 1)
					(thickness 0.15)
				)
			)
		)
		(property "MPN" "GRM155R61H104KE14D"
			(at 0 0 0)
			(layer "F.Fab")
			(hide yes)
			(effects
				(font
					(size 1 1)
					(thickness 0.15)
				)
			)
		)
		(property "Manufacturer" "Murata"
			(at 0 0 0)
			(layer "F.Fab")
			(hide yes)
			(effects
				(font
					(size 1 1)
					(thickness 0.15)
				)
			)
		)
		(property "Val" "100n"
			(at 0 0 0)
			(layer "F.Fab")
			(hide yes)
			(effects
				(font
					(size 1 1)
					(thickness 0.15)
				)
			)
		)
		(property "Voltage" "50V"
			(at 0 0 0)
			(layer "F.Fab")
			(hide yes)
			(effects
				(font
					(size 1 1)
					(thickness 0.15)
				)
			)
		)
		(sheetname "/Supply/")
		(sheetfile "supply.kicad_sch")
		(attr smd)
		(fp_rect
			(start -0.9659 -0.481258)
			(end 0.9649 0.458742)
			(stroke
				(width 0.05)
				(type solid)
			)
			(fill no)
			(layer "F.CrtYd")
		)
		(fp_line
			(start -0.499 -0.25)
			(end 0.499 -0.25)
			(stroke
				(width 0.15)
				(type solid)
			)
			(layer "F.Fab")
		)
		(fp_line
			(start -0.499 0.248)
			(end -0.499 -0.25)
			(stroke
				(width 0.15)
				(type solid)
			)
			(layer "F.Fab")
		)
		(fp_line
			(start 0.499 -0.25)
			(end 0.499 0.248)
			(stroke
				(width 0.15)
				(type solid)
			)
			(layer "F.Fab")
		)
		(fp_line
			(start 0.499 0.248)
			(end -0.499 0.248)
			(stroke
				(width 0.15)
				(type solid)
			)
			(layer "F.Fab")
		)
		(pad "1" smd roundrect
			(at -0.484 0)
			(size 0.59 0.64)
			(layers "F.Cu" "F.Mask" "F.Paste")
			(roundrect_rratio 0.25)
			(net 200 "+3V3")
			(pintype "passive")
		)
		(pad "2" smd roundrect
			(at 0.484 0)
			(size 0.59 0.64)
			(layers "F.Cu" "F.Mask" "F.Paste")
			(roundrect_rratio 0.25)
			(net 1 "GND")
			(pintype "passive")
		)
	)
	(footprint "antmicro-footprints:MP_NPTH_Drill3mm"
		(layer "F.Cu")
		(at 202.878201 115.5)
		(property "Reference" "MP4"
			(at -10.06 1.28 0)
			(layer "F.SilkS")
			(hide yes)
			(effects
				(font
					(size 0.7 0.7)
					(thickness 0.15)
				)
				(justify left bottom)
			)
		)
		(property "Value" "MP_NPTH_Drill3mm"
			(at -13.52 6.2 0)
			(layer "F.Fab")
			(effects
				(font
					(size 0.7 0.7)
					(thickness 0.15)
				)
				(justify left bottom)
			)
		)
		(property "Author" "Antmicro"
			(at 0 0 0)
			(layer "F.Fab")
			(hide yes)
			(effects
				(font
					(size 1 1)
					(thickness 0.15)
				)
			)
		)
		(property "License" "Apache-2.0"
			(at 0 0 0)
			(layer "F.Fab")
			(hide yes)
			(effects
				(font
					(size 1 1)
					(thickness 0.15)
				)
			)
		)
		(sheetfile "sodimm-ddr5-tester.kicad_sch")
		(attr board_only exclude_from_pos_files exclude_from_bom)
		(pad "" np_thru_hole circle
			(at 0 0)
			(size 3 3)
			(drill 3)
			(layers "*.Cu" "*.Mask")
		)
	)
	(footprint "antmicro-footprints:SC70-3"
		(layer "F.Cu")
		(at 91.750501 122.926 90)
		(property "Reference" "Q7"
			(at 0 -1.6 90)
			(layer "F.SilkS")
			(hide yes)
			(effects
				(font
					(size 0.7 0.7)
					(thickness 0.15)
				)
				(justify left bottom)
			)
		)
		(property "Value" "BSS138PW,115"
			(at 0 2.3 90)
			(layer "F.Fab")
			(effects
				(font
					(size 0.7 0.7)
					(thickness 0.15)
				)
				(justify left bottom)
			)
		)
		(property "Datasheet" "https://assets.nexperia.com/documents/data-sheet/BSS138PW.pdf"
			(at 0 0 90)
			(layer "F.Fab")
			(hide yes)
			(effects
				(font
					(size 1.27 1.27)
					(thickness 0.15)
				)
			)
		)
		(property "Description" "Power MOSFET, N Channel, 60 V, 320 mA, 0.9 ohm, SOT-323, Surface Mount"
			(at 0 0 90)
			(layer "F.Fab")
			(hide yes)
			(effects
				(font
					(size 1.27 1.27)
					(thickness 0.15)
				)
			)
		)
		(property "Author" "Antmicro"
			(at 214.676501 31.175499 0)
			(layer "F.Fab")
			(hide yes)
			(effects
				(font
					(size 1 1)
					(thickness 0.15)
				)
			)
		)
		(property "License" "Apache-2.0"
			(at 214.676501 31.175499 0)
			(layer "F.Fab")
			(hide yes)
			(effects
				(font
					(size 1 1)
					(thickness 0.15)
				)
			)
		)
		(property "MPN" "BSS138PW,115"
			(at 214.676501 31.175499 0)
			(layer "F.Fab")
			(hide yes)
			(effects
				(font
					(size 1 1)
					(thickness 0.15)
				)
			)
		)
		(property "Manufacturer" "Nexperia"
			(at 214.676501 31.175499 0)
			(layer "F.Fab")
			(hide yes)
			(effects
				(font
					(size 1 1)
					(thickness 0.15)
				)
			)
		)
		(sheetname "/FPGA bank 14/")
		(sheetfile "fpga-bank-14.kicad_sch")
		(attr smd)
		(fp_line
			(start -0.3 -1)
			(end 0.627 -0.999)
			(stroke
				(width 0.15)
				(type solid)
			)
			(layer "F.SilkS")
		)
		(fp_line
			(start 0.627 -0.6)
			(end 0.627 -0.999)
			(stroke
				(width 0.15)
				(type solid)
			)
			(layer "F.SilkS")
		)
		(fp_line
			(start 0.627 0.6)
			(end 0.627 1.001)
			(stroke
				(width 0.15)
				(type solid)
			)
			(layer "F.SilkS")
		)
		(fp_line
			(start -0.3 1)
			(end 0.627 1.001)
			(stroke
				(width 0.15)
				(type solid)
			)
			(layer "F.SilkS")
		)
		(fp_line
			(start 0.9 -1.3)
			(end 0.9 -0.4)
			(stroke
				(width 0.05)
				(type solid)
			)
			(layer "F.CrtYd")
		)
		(fp_line
			(start -0.9 -1.3)
			(end 0.9 -1.3)
			(stroke
				(width 0.05)
				(type solid)
			)
			(layer "F.CrtYd")
		)
		(fp_line
			(start -0.9 -1.3)
			(end -0.9 -1)
			(stroke
				(width 0.05)
				(type solid)
			)
			(layer "F.CrtYd")
		)
		(fp_line
			(start -0.9 -1)
			(end -1.4 -1)
			(stroke
				(width 0.05)
				(type solid)
			)
			(layer "F.CrtYd")
		)
		(fp_line
			(start 1.4 -0.4)
			(end 1.4 0.4)
			(stroke
				(width 0.05)
				(type solid)
			)
			(layer "F.CrtYd")
		)
		(fp_line
			(start 0.9 -0.4)
			(end 1.4 -0.4)
			(stroke
				(width 0.05)
				(type solid)
			)
			(layer "F.CrtYd")
		)
		(fp_line
			(start 1.4 0.4)
			(end 0.9 0.4)
			(stroke
				(width 0.05)
				(type solid)
			)
			(layer "F.CrtYd")
		)
		(fp_line
			(start 0.9 0.4)
			(end 0.9 1.3)
			(stroke
				(width 0.05)
				(type solid)
			)
			(layer "F.CrtYd")
		)
		(fp_line
			(start -0.9 1)
			(end -1.4 1)
			(stroke
				(width 0.05)
				(type solid)
			)
			(layer "F.CrtYd")
		)
		(fp_line
			(start -1.4 1)
			(end -1.4 -1)
			(stroke
				(width 0.05)
				(type solid)
			)
			(layer "F.CrtYd")
		)
		(fp_line
			(start 0.9 1.3)
			(end -0.9 1.3)
			(stroke
				(width 0.05)
				(type solid)
			)
			(layer "F.CrtYd")
		)
		(fp_line
			(start -0.9 1.3)
			(end -0.9 1)
			(stroke
				(width 0.05)
				(type solid)
			)
			(layer "F.CrtYd")
		)
		(fp_rect
			(start -0.623 -0.999)
			(end 0.627 1.001)
			(stroke
				(width 0.15)
				(type solid)
			)
			(fill no)
			(layer "F.Fab")
		)
		(pad "1" smd rect
			(at -1.051 -0.65 180)
			(size 0.6 0.6)
			(layers "F.Cu" "F.Mask" "F.Paste")
			(net 621 "/FPGA bank 14/USR_LED4")
			(pinfunction "G")
			(pintype "input")
		)
		(pad "2" smd rect
			(at -1.051 0.65 180)
			(size 0.6 0.6)
			(layers "F.Cu" "F.Mask" "F.Paste")
			(net 1 "GND")
			(pinfunction "S")
			(pintype "passive")
		)
		(pad "3" smd rect
			(at 1.05 0 180)
			(size 0.6 0.6)
			(layers "F.Cu" "F.Mask" "F.Paste")
			(net 356 "Net-(Q7-D)")
			(pinfunction "D")
			(pintype "passive")
		)
	)
	(footprint "antmicro-footprints:SC70-3"
		(layer "F.Cu")
		(at 89.050501 122.926 90)
		(property "Reference" "Q5"
			(at 0 -1.6 90)
			(layer "F.SilkS")
			(hide yes)
			(effects
				(font
					(size 0.7 0.7)
					(thickness 0.15)
				)
				(justify left bottom)
			)
		)
		(property "Value" "BSS138PW,115"
			(at 0 2.3 90)
			(layer "F.Fab")
			(effects
				(font
					(size 0.7 0.7)
					(thickness 0.15)
				)
				(justify left bottom)
			)
		)
		(property "Datasheet" "https://assets.nexperia.com/documents/data-sheet/BSS138PW.pdf"
			(at 0 0 90)
			(layer "F.Fab")
			(hide yes)
			(effects
				(font
					(size 1.27 1.27)
					(thickness 0.15)
				)
			)
		)
		(property "Description" "Power MOSFET, N Channel, 60 V, 320 mA, 0.9 ohm, SOT-323, Surface Mount"
			(at 0 0 90)
			(layer "F.Fab")
			(hide yes)
			(effects
				(font
					(size 1.27 1.27)
					(thickness 0.15)
				)
			)
		)
		(property "Author" "Antmicro"
			(at 211.976501 33.875499 0)
			(layer "F.Fab")
			(hide yes)
			(effects
				(font
					(size 1 1)
					(thickness 0.15)
				)
			)
		)
		(property "License" "Apache-2.0"
			(at 211.976501 33.875499 0)
			(layer "F.Fab")
			(hide yes)
			(effects
				(font
					(size 1 1)
					(thickness 0.15)
				)
			)
		)
		(property "MPN" "BSS138PW,115"
			(at 211.976501 33.875499 0)
			(layer "F.Fab")
			(hide yes)
			(effects
				(font
					(size 1 1)
					(thickness 0.15)
				)
			)
		)
		(property "Manufacturer" "Nexperia"
			(at 211.976501 33.875499 0)
			(layer "F.Fab")
			(hide yes)
			(effects
				(font
					(size 1 1)
					(thickness 0.15)
				)
			)
		)
		(sheetname "/FPGA bank 14/")
		(sheetfile "fpga-bank-14.kicad_sch")
		(attr smd)
		(fp_line
			(start -0.3 -1)
			(end 0.627 -0.999)
			(stroke
				(width 0.15)
				(type solid)
			)
			(layer "F.SilkS")
		)
		(fp_line
			(start 0.627 -0.6)
			(end 0.627 -0.999)
			(stroke
				(width 0.15)
				(type solid)
			)
			(layer "F.SilkS")
		)
		(fp_line
			(start 0.627 0.6)
			(end 0.627 1.001)
			(stroke
				(width 0.15)
				(type solid)
			)
			(layer "F.SilkS")
		)
		(fp_line
			(start -0.3 1)
			(end 0.627 1.001)
			(stroke
				(width 0.15)
				(type solid)
			)
			(layer "F.SilkS")
		)
		(fp_line
			(start 0.9 -1.3)
			(end 0.9 -0.4)
			(stroke
				(width 0.05)
				(type solid)
			)
			(layer "F.CrtYd")
		)
		(fp_line
			(start -0.9 -1.3)
			(end 0.9 -1.3)
			(stroke
				(width 0.05)
				(type solid)
			)
			(layer "F.CrtYd")
		)
		(fp_line
			(start -0.9 -1.3)
			(end -0.9 -1)
			(stroke
				(width 0.05)
				(type solid)
			)
			(layer "F.CrtYd")
		)
		(fp_line
			(start -0.9 -1)
			(end -1.4 -1)
			(stroke
				(width 0.05)
				(type solid)
			)
			(layer "F.CrtYd")
		)
		(fp_line
			(start 1.4 -0.4)
			(end 1.4 0.4)
			(stroke
				(width 0.05)
				(type solid)
			)
			(layer "F.CrtYd")
		)
		(fp_line
			(start 0.9 -0.4)
			(end 1.4 -0.4)
			(stroke
				(width 0.05)
				(type solid)
			)
			(layer "F.CrtYd")
		)
		(fp_line
			(start 1.4 0.4)
			(end 0.9 0.4)
			(stroke
				(width 0.05)
				(type solid)
			)
			(layer "F.CrtYd")
		)
		(fp_line
			(start 0.9 0.4)
			(end 0.9 1.3)
			(stroke
				(width 0.05)
				(type solid)
			)
			(layer "F.CrtYd")
		)
		(fp_line
			(start -0.9 1)
			(end -1.4 1)
			(stroke
				(width 0.05)
				(type solid)
			)
			(layer "F.CrtYd")
		)
		(fp_line
			(start -1.4 1)
			(end -1.4 -1)
			(stroke
				(width 0.05)
				(type solid)
			)
			(layer "F.CrtYd")
		)
		(fp_line
			(start 0.9 1.3)
			(end -0.9 1.3)
			(stroke
				(width 0.05)
				(type solid)
			)
			(layer "F.CrtYd")
		)
		(fp_line
			(start -0.9 1.3)
			(end -0.9 1)
			(stroke
				(width 0.05)
				(type solid)
			)
			(layer "F.CrtYd")
		)
		(fp_rect
			(start -0.623 -0.999)
			(end 0.627 1.001)
			(stroke
				(width 0.15)
				(type solid)
			)
			(fill no)
			(layer "F.Fab")
		)
		(pad "1" smd rect
			(at -1.051 -0.65 180)
			(size 0.6 0.6)
			(layers "F.Cu" "F.Mask" "F.Paste")
			(net 617 "/FPGA bank 14/USR_LED3")
			(pinfunction "G")
			(pintype "input")
		)
		(pad "2" smd rect
			(at -1.051 0.65 180)
			(size 0.6 0.6)
			(layers "F.Cu" "F.Mask" "F.Paste")
			(net 1 "GND")
			(pinfunction "S")
			(pintype "passive")
		)
		(pad "3" smd rect
			(at 1.05 0 180)
			(size 0.6 0.6)
			(layers "F.Cu" "F.Mask" "F.Paste")
			(net 354 "Net-(Q5-D)")
			(pinfunction "D")
			(pintype "passive")
		)
	)
	(footprint "antmicro-footprints:SOT-23-6"
		(layer "F.Cu")
		(at 196.6 139.265 90)
		(property "Reference" "U22"
			(at -0.835 2.7 90)
			(layer "F.SilkS")
			(effects
				(font
					(size 0.7 0.7)
					(thickness 0.15)
				)
				(justify left bottom)
			)
		)
		(property "Value" "MAX16150A_SOT"
			(at -1.75 2.75 90)
			(layer "F.Fab")
			(effects
				(font
					(size 0.7 0.7)
					(thickness 0.15)
				)
				(justify left bottom)
			)
		)
		(property "Datasheet" "https://datasheets.maximintegrated.com/en/ds/MAX16150.pdf"
			(at 0 0 90)
			(layer "F.Fab")
			(hide yes)
			(effects
				(font
					(size 1.27 1.27)
					(thickness 0.15)
				)
			)
		)
		(property "Author" "Antmicro"
			(at 335.865 -57.335 0)
			(layer "F.Fab")
			(hide yes)
			(effects
				(font
					(size 1 1)
					(thickness 0.15)
				)
			)
		)
		(property "License" "Apache-2.0"
			(at 335.865 -57.335 0)
			(layer "F.Fab")
			(hide yes)
			(effects
				(font
					(size 1 1)
					(thickness 0.15)
				)
			)
		)
		(property "MPN" "MAX16150AUT+T"
			(at 335.865 -57.335 0)
			(layer "F.Fab")
			(hide yes)
			(effects
				(font
					(size 1 1)
					(thickness 0.15)
				)
			)
		)
		(property "Manufacturer" "Maxim Integrated Products"
			(at 335.865 -57.335 0)
			(layer "F.Fab")
			(hide yes)
			(effects
				(font
					(size 1 1)
					(thickness 0.15)
				)
			)
		)
		(sheetname "/Supply/")
		(sheetfile "supply.kicad_sch")
		(attr smd)
		(fp_line
			(start 1.45 -0.7)
			(end 1.45 -0.4)
			(stroke
				(width 0.12)
				(type solid)
			)
			(layer "F.SilkS")
		)
		(fp_line
			(start 1.3 -0.7)
			(end 1.45 -0.7)
			(stroke
				(width 0.12)
				(type solid)
			)
			(layer "F.SilkS")
		)
		(fp_line
			(start -1.3 -0.7)
			(end -1.45 -0.7)
			(stroke
				(width 0.12)
				(type solid)
			)
			(layer "F.SilkS")
		)
		(fp_line
			(start -1.45 -0.7)
			(end -1.45 -0.4)
			(stroke
				(width 0.12)
				(type solid)
			)
			(layer "F.SilkS")
		)
		(fp_line
			(start 1.45 0.7)
			(end 1.45 0.4)
			(stroke
				(width 0.12)
				(type solid)
			)
			(layer "F.SilkS")
		)
		(fp_line
			(start 1.3 0.7)
			(end 1.45 0.7)
			(stroke
				(width 0.12)
				(type solid)
			)
			(layer "F.SilkS")
		)
		(fp_line
			(start -1.45 0.7)
			(end -1.45 0.4)
			(stroke
				(width 0.12)
				(type solid)
			)
			(layer "F.SilkS")
		)
		(fp_rect
			(start -1.55 -1.85)
			(end 1.55 1.75)
			(stroke
				(width 0.05)
				(type solid)
			)
			(fill no)
			(layer "F.CrtYd")
		)
		(fp_line
			(start 1.5 -0.7)
			(end 1.5 0.7)
			(stroke
				(width 0.1)
				(type solid)
			)
			(layer "F.Fab")
		)
		(fp_line
			(start -1.5 -0.7)
			(end 1.5 -0.7)
			(stroke
				(width 0.1)
				(type solid)
			)
			(layer "F.Fab")
		)
		(fp_line
			(start 1.5 0.7)
			(end -1.5 0.7)
			(stroke
				(width 0.1)
				(type solid)
			)
			(layer "F.Fab")
		)
		(fp_line
			(start -1.5 0.7)
			(end -1.5 -0.7)
			(stroke
				(width 0.1)
				(type solid)
			)
			(layer "F.Fab")
		)
		(fp_text user "."
			(at -1.4 1.2 270)
			(layer "F.SilkS")
			(effects
				(font
					(size 1 1)
					(thickness 0.15)
				)
			)
		)
		(pad "1" smd roundrect
			(at -0.954 1.1 90)
			(size 0.55 1)
			(layers "F.Cu" "F.Mask" "F.Paste")
			(roundrect_rratio 0.15)
			(net 252 "/Supply/~{PB_CTRL_IN}")
			(pinfunction "~{PB_IN}")
			(pintype "input")
		)
		(pad "2" smd roundrect
			(at -0.003 1.1 90)
			(size 0.55 1)
			(layers "F.Cu" "F.Mask" "F.Paste")
			(roundrect_rratio 0.15)
			(net 1 "GND")
			(pinfunction "GND")
			(pintype "power_in")
		)
		(pad "3" smd roundrect
			(at 0.947 1.1 90)
			(size 0.55 1)
			(layers "F.Cu" "F.Mask" "F.Paste")
			(roundrect_rratio 0.15)
			(net 41 "+3V3_AON")
			(pinfunction "VCC")
			(pintype "power_in")
		)
		(pad "4" smd roundrect
			(at 0.947 -1.214 90)
			(size 0.55 1)
			(layers "F.Cu" "F.Mask" "F.Paste")
			(roundrect_rratio 0.15)
			(net 186 "/Supply/PB_CTRL_OUT")
			(pinfunction "OUT")
			(pintype "output")
		)
		(pad "5" smd roundrect
			(at -0.003 -1.214 90)
			(size 0.55 1)
			(layers "F.Cu" "F.Mask" "F.Paste")
			(roundrect_rratio 0.15)
			(net 207 "/Supply/~{PB_CTRL_INT}")
			(pinfunction "~{INT}")
			(pintype "output")
		)
		(pad "6" smd roundrect
			(at -0.954 -1.214 90)
			(size 0.55 1)
			(layers "F.Cu" "F.Mask" "F.Paste")
			(roundrect_rratio 0.15)
			(net 185 "/Supply/~{PB_CTRL_CLR}")
			(pinfunction "~{CLR}")
			(pintype "input")
		)
	)
)
